Created on Valor NPI 9.6 Update 2 - Netlist Compare Summary.
DATE :  07 Aug 2017
TIME :  13:44:26


     MISMATCH SUMMARY REPORT
     -----------------------

Job  : 16318-2                 Job  : 16318-2
Step : q                       Step : q
Type : CAD                     Type : CURCAD

-----------------------------------------------

 Mismatch Type: shorted

   GND                   -   NET00000            
   AGND_P1V8_STBY        -    "                  
   AGND_P5V              -    "                  
   AGND_P3V3_STBY        -    "                  
   AGND_CURRENT_MON      -    "                  
   AGND_P0V975           -    "                  
   P5V_STBY              -   NET00037            
   P5V_CC                -    "                  
   P1V8_STBY             -   NET00615            
   P1V8_STBY_CC          -    "                  

 Total : 3
-----------------------------------------------

 Mismatch Type: broken


 Total : 0
-----------------------------------------------

 Mismatch Type: missing


 Total : 0
-----------------------------------------------

 Mismatch Type: extra


 Total : 0
-----------------------------------------------
